(kicad_pcb
	(version 20241229)
	(generator "pcbnew")
	(generator_version "9.0")
	(general
		(thickness 1.61)
		(legacy_teardrops no)
	)
	(paper "A3")
	(title_block
		(title "SO-DIMM DDR5 Tester")
		(date "2025-11-26")
		(rev "1.3.0")
		(comment 9 "footprints 143-146 of 627")
	)
	(layers
		(0 "F.Cu" signal)
		(4 "In1.Cu" power)
		(6 "In2.Cu" mixed)
		(8 "In3.Cu" power)
		(10 "In4.Cu" mixed)
		(12 "In5.Cu" power)
		(14 "In6.Cu" mixed)
		(16 "In7.Cu" power)
		(18 "In8.Cu" power)
		(20 "In9.Cu" mixed)
		(22 "In10.Cu" power)
		(2 "B.Cu" signal)
		(9 "F.Adhes" user "F.Adhesive")
		(11 "B.Adhes" user "B.Adhesive")
		(13 "F.Paste" user)
		(15 "B.Paste" user)
		(5 "F.SilkS" user "F.Silkscreen")
		(7 "B.SilkS" user "B.Silkscreen")
		(1 "F.Mask" user)
		(3 "B.Mask" user)
		(17 "Dwgs.User" user "User.Drawings")
		(19 "Cmts.User" user "User.Comments")
		(21 "Eco1.User" user "User.Eco1")
		(23 "Eco2.User" user "User.Eco2")
		(25 "Edge.Cuts" user)
		(27 "Margin" user)
		(31 "F.CrtYd" user "F.Courtyard")
		(29 "B.CrtYd" user "B.Courtyard")
		(35 "F.Fab" user)
		(33 "B.Fab" user)
	)
	(footprint "antmicro-footprints:RJ45_ARJM11B1-502-AB-EW2_Horizontal"
		(layer "F.Cu")
		(at 86.9805 131.804037 -90)
		(descr "ARJM11B1-502-AB-EW2 RJ45 JACK")
		(property "Reference" "J6"
			(at -2.214037 -2.1095 90)
			(layer "F.SilkS")
			(effects
				(font
					(size 0.7 0.7)
					(thickness 0.15)
				)
				(justify right top)
			)
		)
		(property "Value" "RJ45_Abracon_ARJM11B1-502-AB-EW2"
			(at -4.3 22.78 90)
			(layer "F.Fab")
			(effects
				(font
					(size 0.7 0.7)
					(thickness 0.15)
				)
				(justify right top)
			)
		)
		(property "Datasheet" "https://www.mouser.com/datasheet/3/184/1/ARJM11.pdf"
			(at -0.035 -0.01 90)
			(layer "F.Fab")
			(effects
				(font
					(size 0.7 0.7)
					(thickness 0.15)
				)
				(justify right top)
			)
		)
		(property "Description" "Modular Connectors / Ethernet Connectors RJ45 JACK W/MAG 1X1 1000BASE-T"
			(at -0.035 -0.01 90)
			(layer "F.Fab")
			(effects
				(font
					(size 0.7 0.7)
					(thickness 0.15)
				)
				(justify right top)
			)
		)
		(property "MPN" "ARJM11B1-502-AB-EW2"
			(at 0 0 270)
			(unlocked yes)
			(layer "F.Fab")
			(hide yes)
			(effects
				(font
					(size 1 1)
					(thickness 0.15)
				)
			)
		)
		(property "Manufacturer" "Abracon"
			(at 0 0 270)
			(unlocked yes)
			(layer "F.Fab")
			(hide yes)
			(effects
				(font
					(size 1 1)
					(thickness 0.15)
				)
			)
		)
		(property "Author" "Antmicro"
			(at 0 0 270)
			(unlocked yes)
			(layer "F.Fab")
			(hide yes)
			(effects
				(font
					(size 1 1)
					(thickness 0.15)
				)
			)
		)
		(property "License" "Apache-2.0"
			(at 0 0 270)
			(unlocked yes)
			(layer "F.Fab")
			(hide yes)
			(effects
				(font
					(size 1 1)
					(thickness 0.15)
				)
			)
		)
		(sheetname "/Ethernet/")
		(sheetfile "ethernet.kicad_sch")
		(attr through_hole)
		(fp_line
			(start -2.235 19.69)
			(end 13.665 19.69)
			(stroke
				(width 0.15)
				(type solid)
			)
			(layer "F.SilkS")
		)
		(fp_line
			(start -2.235 19.69)
			(end -2.235 7.48)
			(stroke
				(width 0.15)
				(type solid)
			)
			(layer "F.SilkS")
		)
		(fp_line
			(start 13.665 19.69)
			(end 13.665 7.48)
			(stroke
				(width 0.15)
				(type solid)
			)
			(layer "F.SilkS")
		)
		(fp_line
			(start 13.665 4.19)
			(end 13.665 -1.51)
			(stroke
				(width 0.15)
				(type solid)
			)
			(layer "F.SilkS")
		)
		(fp_line
			(start -2.235 -1.51)
			(end -2.235 4.19)
			(stroke
				(width 0.15)
				(type solid)
			)
			(layer "F.SilkS")
		)
		(fp_line
			(start 13.665 -1.51)
			(end -2.235 -1.51)
			(stroke
				(width 0.15)
				(type solid)
			)
			(layer "F.SilkS")
		)
		(fp_line
			(start -3.7 19.94)
			(end 15.12 19.94)
			(stroke
				(width 0.05)
				(type solid)
			)
			(layer "F.CrtYd")
		)
		(fp_line
			(start 15.12 19.94)
			(end 15.12 -1.76)
			(stroke
				(width 0.05)
				(type solid)
			)
			(layer "F.CrtYd")
		)
		(fp_line
			(start -3.7 -1.76)
			(end -3.7 19.94)
			(stroke
				(width 0.05)
				(type solid)
			)
			(layer "F.CrtYd")
		)
		(fp_line
			(start 15.12 -1.76)
			(end -3.7 -1.76)
			(stroke
				(width 0.05)
				(type solid)
			)
			(layer "F.CrtYd")
		)
		(fp_line
			(start -2.235 19.69)
			(end 13.665 19.69)
			(stroke
				(width 0.15)
				(type solid)
			)
			(layer "F.Fab")
		)
		(fp_line
			(start 13.665 19.69)
			(end 13.665 -1.51)
			(stroke
				(width 0.15)
				(type solid)
			)
			(layer "F.Fab")
		)
		(fp_line
			(start -2.235 -1.51)
			(end -2.235 19.69)
			(stroke
				(width 0.15)
				(type solid)
			)
			(layer "F.Fab")
		)
		(fp_line
			(start 13.665 -1.51)
			(end -2.235 -1.51)
			(stroke
				(width 0.15)
				(type solid)
			)
			(layer "F.Fab")
		)
		(fp_text user "License: Apache-2.0"
			(at -4.3 25.18 90)
			(layer "F.Fab")
			(effects
				(font
					(size 0.7 0.7)
					(thickness 0.15)
				)
				(justify right top)
			)
		)
		(fp_text user "Author: Antmicro"
			(at -4.3 23.98 90)
			(layer "F.Fab")
			(effects
				(font
					(size 0.7 0.7)
					(thickness 0.15)
				)
				(justify right top)
			)
		)
		(fp_text user "${REFERENCE}"
			(at -4.26 21.29 90)
			(layer "F.Fab")
			(effects
				(font
					(size 0.7 0.7)
					(thickness 0.15)
				)
				(justify right top)
			)
		)
		(pad "" np_thru_hole circle
			(at 0 8.89 270)
			(size 3.2 3.2)
			(drill 3.25)
			(layers "*.Cu" "*.Mask")
		)
		(pad "" np_thru_hole circle
			(at 11.43 8.89 270)
			(size 3.2 3.2)
			(drill 3.25)
			(layers "*.Cu" "*.Mask")
		)
		(pad "1" thru_hole circle
			(at 0 0 270)
			(size 1.458 1.458)
			(drill 0.9)
			(layers "*.Cu" "*.Mask")
			(remove_unused_layers no)
			(net 125 "/Ethernet/ETH1_P")
			(pinfunction "1")
			(pintype "bidirectional")
			(solder_mask_margin 0)
		)
		(pad "2" thru_hole circle
			(at 1.27 2.54 270)
			(size 1.458 1.458)
			(drill 0.9)
			(layers "*.Cu" "*.Mask")
			(remove_unused_layers no)
			(net 128 "/Ethernet/ETH1_N")
			(pinfunction "2")
			(pintype "bidirectional")
			(solder_mask_margin 0)
		)
		(pad "3" thru_hole circle
			(at 2.54 0 270)
			(size 1.458 1.458)
			(drill 0.9)
			(layers "*.Cu" "*.Mask")
			(remove_unused_layers no)
			(net 124 "/Ethernet/ETH2_P")
			(pinfunction "3")
			(pintype "bidirectional")
			(solder_mask_margin 0)
		)
		(pad "4" thru_hole circle
			(at 3.81 2.54 270)
			(size 1.458 1.458)
			(drill 0.9)
			(layers "*.Cu" "*.Mask")
			(remove_unused_layers no)
			(net 127 "/Ethernet/ETH2_N")
			(pinfunction "4")
			(pintype "bidirectional")
			(solder_mask_margin 0)
		)
		(pad "5" thru_hole circle
			(at 5.08 0 270)
			(size 1.458 1.458)
			(drill 0.9)
			(layers "*.Cu" "*.Mask")
			(remove_unused_layers no)
			(net 215 "Net-(C137-Pad2)")
			(pinfunction "5")
			(pintype "passive")
			(solder_mask_margin 0)
		)
		(pad "6" thru_hole circle
			(at 6.35 2.54 270)
			(size 1.458 1.458)
			(drill 0.9)
			(layers "*.Cu" "*.Mask")
			(remove_unused_layers no)
			(net 214 "Net-(C135-Pad2)")
			(pinfunction "6")
			(pintype "passive")
			(solder_mask_margin 0)
		)
		(pad "7" thru_hole circle
			(at 7.62 0 270)
			(size 1.458 1.458)
			(drill 0.9)
			(layers "*.Cu" "*.Mask")
			(remove_unused_layers no)
			(net 123 "/Ethernet/ETH3_P")
			(pinfunction "7")
			(pintype "bidirectional")
			(solder_mask_margin 0)
		)
		(pad "8" thru_hole circle
			(at 8.89 2.54 270)
			(size 1.458 1.458)
			(drill 0.9)
			(layers "*.Cu" "*.Mask")
			(remove_unused_layers no)
			(net 129 "/Ethernet/ETH3_N")
			(pinfunction "8")
			(pintype "bidirectional")
			(solder_mask_margin 0)
		)
		(pad "9" thru_hole circle
			(at 10.16 0 270)
			(size 1.458 1.458)
			(drill 0.9)
			(layers "*.Cu" "*.Mask")
			(remove_unused_layers no)
			(net 126 "/Ethernet/ETH4_P")
			(pinfunction "9")
			(pintype "bidirectional")
			(solder_mask_margin 0)
		)
		(pad "10" thru_hole circle
			(at 11.43 2.54 270)
			(size 1.458 1.458)
			(drill 0.9)
			(layers "*.Cu" "*.Mask")
			(remove_unused_layers no)
			(net 130 "/Ethernet/ETH4_N")
			(pinfunction "10")
			(pintype "bidirectional")
			(solder_mask_margin 0)
		)
		(pad "11" thru_hole circle
			(at -0.96 12.95 270)
			(size 1.605 1.605)
			(drill 1.02)
			(layers "*.Cu" "*.Mask")
			(remove_unused_layers no)
			(net 758 "Net-(J6-LED_G+)")
			(pinfunction "LED_G+")
			(pintype "passive")
			(solder_mask_margin 0)
		)
		(pad "12" thru_hole circle
			(at 1.58 12.95 270)
			(size 1.605 1.605)
			(drill 1.02)
			(layers "*.Cu" "*.Mask")
			(remove_unused_layers no)
			(net 602 "/Ethernet/LED_SPD")
			(pinfunction "LED_G-")
			(pintype "passive")
			(solder_mask_margin 0)
		)
		(pad "13" thru_hole circle
			(at 9.85 12.95 270)
			(size 1.605 1.605)
			(drill 1.02)
			(layers "*.Cu" "*.Mask")
			(remove_unused_layers no)
			(net 757 "Net-(J6-LED_Y+)")
			(pinfunction "LED_Y+")
			(pintype "passive")
			(solder_mask_margin 0)
		)
		(pad "14" thru_hole circle
			(at 12.39 12.95 270)
			(size 1.605 1.605)
			(drill 1.02)
			(layers "*.Cu" "*.Mask")
			(remove_unused_layers no)
			(net 603 "/Ethernet/LED_LINK")
			(pinfunction "LED_Y-")
			(pintype "passive")
			(solder_mask_margin 0)
		)
		(pad "SH" thru_hole circle
			(at -2.135 5.84 270)
			(size 2.625 2.625)
			(drill 1.7)
			(layers "*.Cu" "*.Mask")
			(remove_unused_layers no)
			(net 32 "Net-(C234-Pad1)")
			(pinfunction "SH")
			(pintype "passive")
			(solder_mask_margin 0)
		)
		(pad "SH" thru_hole circle
			(at 13.565 5.84 270)
			(size 2.625 2.625)
			(drill 1.7)
			(layers "*.Cu" "*.Mask")
			(remove_unused_layers no)
			(net 32 "Net-(C234-Pad1)")
			(pinfunction "SH")
			(pintype "passive")
			(solder_mask_margin 0)
		)
	)
	(footprint "antmicro-footprints:Torex_USP-6C"
		(layer "F.Cu")
		(at 194.175 194.85)
		(tags "Integrated Circuit")
		(property "Reference" "U28"
			(at -0.575 2.35 0)
			(layer "F.SilkS")
			(effects
				(font
					(size 0.7 0.7)
					(thickness 0.15)
				)
				(justify left bottom)
			)
		)
		(property "Value" "XC6230H001ER-G"
			(at -3.492 1.929 0)
			(layer "F.Fab")
			(effects
				(font
					(size 0.7 0.7)
					(thickness 0.15)
				)
				(justify left bottom)
			)
		)
		(property "Datasheet" "https://www.torexsemi.com/file/xc6230/XC6230.pdf"
			(at 0 0 0)
			(layer "F.Fab")
			(hide yes)
			(effects
				(font
					(size 1.27 1.27)
					(thickness 0.15)
				)
			)
		)
		(property "Author" "Antmicro"
			(at 0 0 0)
			(layer "F.Fab")
			(hide yes)
			(effects
				(font
					(size 1 1)
					(thickness 0.15)
				)
			)
		)
		(property "License" "Apache-2.0"
			(at 0 0 0)
			(layer "F.Fab")
			(hide yes)
			(effects
				(font
					(size 1 1)
					(thickness 0.15)
				)
			)
		)
		(property "MPN" "XC6230H001ER-G"
			(at 0 0 0)
			(layer "F.Fab")
			(hide yes)
			(effects
				(font
					(size 1 1)
					(thickness 0.15)
				)
			)
		)
		(property "Manufacturer" "Torex Semiconductor"
			(at 0 0 0)
			(layer "F.Fab")
			(hide yes)
			(effects
				(font
					(size 1 1)
					(thickness 0.15)
				)
			)
		)
		(sheetname "/Supply/")
		(sheetfile "supply.kicad_sch")
		(attr smd)
		(fp_circle
			(center -1.801 -0.554)
			(end -1.751 -0.554)
			(stroke
				(width 0.15)
				(type solid)
			)
			(fill yes)
			(layer "F.SilkS")
		)
		(fp_rect
			(start -0.403 -0.701)
			(end 0.4 -0.203)
			(stroke
				(width 0.01)
				(type solid)
			)
			(fill yes)
			(layer "F.Paste")
		)
		(fp_rect
			(start -0.403 0.2)
			(end 0.4 0.698)
			(stroke
				(width 0.01)
				(type solid)
			)
			(fill yes)
			(layer "F.Paste")
		)
		(fp_rect
			(start -1.5 -1.402)
			(end 1.498 1.4)
			(stroke
				(width 0.05)
				(type solid)
			)
			(fill no)
			(layer "F.CrtYd")
		)
		(fp_line
			(start -1 -0.903)
			(end 0.997 -0.903)
			(stroke
				(width 0.15)
				(type solid)
			)
			(layer "F.Fab")
		)
		(fp_line
			(start -1 -0.7)
			(end -0.8 -0.9)
			(stroke
				(width 0.15)
				(type solid)
			)
			(layer "F.Fab")
		)
		(fp_line
			(start -1 0.9)
			(end -1 -0.903)
			(stroke
				(width 0.15)
				(type solid)
			)
			(layer "F.Fab")
		)
		(fp_line
			(start 0.997 -0.903)
			(end 0.997 0.9)
			(stroke
				(width 0.15)
				(type solid)
			)
			(layer "F.Fab")
		)
		(fp_line
			(start 0.997 0.9)
			(end -1 0.9)
			(stroke
				(width 0.15)
				(type solid)
			)
			(layer "F.Fab")
		)
		(pad "1" smd rect
			(at -0.975 -0.553 90)
			(size 0.35 0.45)
			(layers "F.Cu" "F.Mask" "F.Paste")
			(net 76 "/Supply/MGTAVTT_OUT")
			(pinfunction "OUT")
			(pintype "power_out")
		)
		(pad "2" smd rect
			(at -0.975 0 90)
			(size 0.25 0.45)
			(layers "F.Cu" "F.Mask" "F.Paste")
			(net 224 "/Supply/MGTAVTT_ILIM")
			(pinfunction "ILIM")
			(pintype "output")
		)
		(pad "3" smd rect
			(at -0.975 0.497 90)
			(size 0.25 0.45)
			(layers "F.Cu" "F.Mask" "F.Paste")
			(net 76 "/Supply/MGTAVTT_OUT")
			(pinfunction "FB")
			(pintype "open_collector")
		)
		(pad "4" smd rect
			(at 0.972 0.497 90)
			(size 0.25 0.45)
			(layers "F.Cu" "F.Mask" "F.Paste")
			(net 64 "/Supply/1V7")
			(pinfunction "EN")
			(pintype "input")
		)
		(pad "5" smd rect
			(at 0.972 0 90)
			(size 0.25 0.45)
			(layers "F.Cu" "F.Mask" "F.Paste")
			(net 1 "GND")
			(pinfunction "GND")
			(pintype "power_in")
		)
		(pad "6" smd rect
			(at 0.972 -0.5 90)
			(size 0.25 0.45)
			(layers "F.Cu" "F.Mask" "F.Paste")
			(net 64 "/Supply/1V7")
			(pinfunction "IN")
			(pintype "power_out")
		)
		(pad "7" smd rect
			(at 0 0)
			(size 1 1.6)
			(layers "F.Cu" "F.Mask")
			(net 1 "GND")
			(pinfunction "EP")
			(pintype "passive")
		)
		(pad "7" smd rect
			(at 0 0 90)
			(size 1.8 0.9)
			(layers "F.Cu" "F.Mask")
			(net 1 "GND")
			(pinfunction "EP")
			(pintype "passive")
		)
	)
	(footprint "antmicro-footprints:R_0402_1005Metric"
		(layer "F.Cu")
		(at 177.9 179.115)
		(descr "Resistor SMD 0402")
		(tags "resistor SMD 0402")
		(property "Reference" "R135"
			(at -1.122484 -0.772697 0)
			(layer "F.SilkS")
			(hide yes)
			(effects
				(font
					(size 0.7 0.7)
					(thickness 0.15)
				)
				(justify left bottom)
			)
		)
		(property "Value" "R_47k_0402"
			(at -1.011843 1.772047 0)
			(layer "F.Fab")
			(effects
				(font
					(size 0.7 0.7)
					(thickness 0.15)
				)
				(justify left bottom)
			)
		)
		(property "Datasheet" "https://www.bourns.com/docs/product-datasheets/cr.pdf"
			(at 0 0 0)
			(layer "F.Fab")
			(hide yes)
			(effects
				(font
					(size 1.27 1.27)
					(thickness 0.15)
				)
			)
		)
		(property "Author" "Antmicro"
			(at 0 0 0)
			(layer "F.Fab")
			(hide yes)
			(effects
				(font
					(size 1 1)
					(thickness 0.15)
				)
			)
		)
		(property "License" "Apache-2.0"
			(at 0 0 0)
			(layer "F.Fab")
			(hide yes)
			(effects
				(font
					(size 1 1)
					(thickness 0.15)
				)
			)
		)
		(property "MPN" "CR0402-FX-4702GLF"
			(at 0 0 0)
			(layer "F.Fab")
			(hide yes)
			(effects
				(font
					(size 1 1)
					(thickness 0.15)
				)
			)
		)
		(property "Manufacturer" "Bourns"
			(at 0 0 0)
			(layer "F.Fab")
			(hide yes)
			(effects
				(font
					(size 1 1)
					(thickness 0.15)
				)
			)
		)
		(property "Tolerance" "1%"
			(at 0 0 0)
			(layer "F.Fab")
			(hide yes)
			(effects
				(font
					(size 1 1)
					(thickness 0.15)
				)
			)
		)
		(property "Val" "47k"
			(at 0 0 0)
			(layer "F.Fab")
			(hide yes)
			(effects
				(font
					(size 1 1)
					(thickness 0.15)
				)
			)
		)
		(sheetname "/Supply/")
		(sheetfile "supply.kicad_sch")
		(attr smd)
		(fp_rect
			(start -0.93 -0.47)
			(end 0.93 0.47)
			(stroke
				(width 0.05)
				(type solid)
			)
			(fill no)
			(layer "F.CrtYd")
		)
		(fp_rect
			(start -0.5 -0.25)
			(end 0.5 0.25)
			(stroke
				(width 0.15)
				(type solid)
			)
			(fill no)
			(layer "F.Fab")
		)
		(pad "1" smd roundrect
			(at -0.485 0)
			(size 0.59 0.64)
			(layers "F.Cu" "F.Mask" "F.Paste")
			(roundrect_rratio 0.25)
			(net 240 "POWER")
			(pintype "passive")
		)
		(pad "2" smd roundrect
			(at 0.485 0)
			(size 0.59 0.64)
			(layers "F.Cu" "F.Mask" "F.Paste")
			(roundrect_rratio 0.25)
			(net 200 "+3V3")
			(pintype "passive")
		)
	)
	(footprint "antmicro-footprints:R_0402_1005Metric"
		(layer "F.Cu")
		(at 94.450501 119.926 -90)
		(descr "Resistor SMD 0402")
		(tags "resistor SMD 0402")
		(property "Reference" "R46"
			(at -1.122484 -0.772697 270)
			(layer "F.SilkS")
			(hide yes)
			(effects
				(font
					(size 0.7 0.7)
					(thickness 0.15)
				)
				(justify left bottom)
			)
		)
		(property "Value" "R_330R_0402"
			(at -1.011843 1.772047 270)
			(layer "F.Fab")
			(effects
				(font
					(size 0.7 0.7)
					(thickness 0.15)
				)
				(justify left bottom)
			)
		)
		(property "Datasheet" "https://www.bourns.com/docs/product-datasheets/cr.pdf"
			(at 0 0 270)
			(layer "F.Fab")
			(hide yes)
			(effects
				(font
					(size 1.27 1.27)
					(thickness 0.15)
				)
			)
		)
		(property "Author" "Antmicro"
			(at -25.475499 214.376501 0)
			(layer "F.Fab")
			(hide yes)
			(effects
				(font
					(size 1 1)
					(thickness 0.15)
				)
			)
		)
		(property "License" "Apache-2.0"
			(at -25.475499 214.376501 0)
			(layer "F.Fab")
			(hide yes)
			(effects
				(font
					(size 1 1)
					(thickness 0.15)
				)
			)
		)
		(property "MPN" "CR0402-FX-3300GLF"
			(at -25.475499 214.376501 0)
			(layer "F.Fab")
			(hide yes)
			(effects
				(font
					(size 1 1)
					(thickness 0.15)
				)
			)
		)
		(property "Manufacturer" "Bourns"
			(at -25.475499 214.376501 0)
			(layer "F.Fab")
			(hide yes)
			(effects
				(font
					(size 1 1)
					(thickness 0.15)
				)
			)
		)
		(property "Tolerance" "1%"
			(at -25.475499 214.376501 0)
			(layer "F.Fab")
			(hide yes)
			(effects
				(font
					(size 1 1)
					(thickness 0.15)
				)
			)
		)
		(property "Val" "330R"
			(at -25.475499 214.376501 0)
			(layer "F.Fab")
			(hide yes)
			(effects
				(font
					(size 1 1)
					(thickness 0.15)
				)
			)
		)
		(sheetname "/FPGA bank 14/")
		(sheetfile "fpga-bank-14.kicad_sch")
		(attr smd)
		(fp_rect
			(start -0.93 -0.47)
			(end 0.93 0.47)
			(stroke
				(width 0.05)
				(type solid)
			)
			(fill no)
			(layer "F.CrtYd")
		)
		(fp_rect
			(start -0.5 -0.25)
			(end 0.5 0.25)
			(stroke
				(width 0.15)
				(type solid)
			)
			(fill no)
			(layer "F.Fab")
		)
		(pad "1" smd roundrect
			(at -0.485 0 270)
			(size 0.59 0.64)
			(layers "F.Cu" "F.Mask" "F.Paste")
			(roundrect_rratio 0.25)
			(net 33 "Net-(D8-Pad2)")
			(pintype "passive")
		)
		(pad "2" smd roundrect
			(at 0.485 0 270)
			(size 0.59 0.64)
			(layers "F.Cu" "F.Mask" "F.Paste")
			(roundrect_rratio 0.25)
			(net 357 "Net-(Q8-D)")
			(pintype "passive")
		)
	)
)
